# S9S_MB_2U (Grand Teton) — schematic netlist excerpt (pin names and nets, part order shuffled) for the footprints in the layout excerpt that follows; sources: Cadence DE-HDL packaged netlist, KiCad conversion of 03242023_DA0F0TMBIJ0_F0T_Motherboard_J_brd_V01_OCP.brd

R4620  Q_RES  4.7K 5% CHIP  pkg 0402LF  page 306 : A = P3V3_AUX ; B = IRQ_UV_DETECT_N
C1009  Q_CAP  22UF 4V 20% X6S  pkg C0402  page 74 : A = PVCCIN_CPU0 ; B = GND

(kicad_pcb
	(version 20260206)
	(generator "pcbnew")
	(generator_version "10.0")
	(general
		(thickness 1.6)
		(legacy_teardrops no)
	)
	(paper "A4")
	(title_block
		(title "03242023_DA0F0TMBIJ0_F0T_Motherboard_J_brd_V01_OCP.brd")
		(comment 1 "Grand Teton / footprints 1004-1005 of 6105")
	)
	(layers
		(0 "F.Cu" signal "TOP")
		(4 "In1.Cu" signal "GND")
		(6 "In2.Cu" signal "IN1")
		(8 "In3.Cu" signal "GND1")
		(10 "In4.Cu" signal "IN2")
		(12 "In5.Cu" signal "GND2")
		(14 "In6.Cu" signal "IN3")
		(16 "In7.Cu" signal "GND3")
		(18 "In8.Cu" signal "VCC")
		(20 "In9.Cu" signal "VCC1")
		(22 "In10.Cu" signal "GND4")
		(24 "In11.Cu" signal "IN4")
		(26 "In12.Cu" signal "GND5")
		(28 "In13.Cu" signal "IN5")
		(30 "In14.Cu" signal "GND6")
		(32 "In15.Cu" signal "IN6")
		(34 "In16.Cu" signal "GND7")
		(2 "B.Cu" signal "BOTTOM")
		(9 "F.Adhes" user "F.Adhesive")
		(11 "B.Adhes" user "B.Adhesive")
		(13 "F.Paste" user "Package Geometry/Pastemask Top")
		(15 "B.Paste" user "Package Geometry/Pastemask Bottom")
		(5 "F.SilkS" user "Ref Des/Silkscreen Top")
		(7 "B.SilkS" user "Ref Des/Silkscreen Bottom")
		(1 "F.Mask" user "Board Geometry/Soldermask Top")
		(3 "B.Mask" user "Board Geometry/Soldermask Bottom")
		(17 "Dwgs.User" user "User.Drawings")
		(19 "Cmts.User" user "User.Comments")
		(21 "Eco1.User" user "User.Eco1")
		(23 "Eco2.User" user "User.Eco2")
		(25 "Edge.Cuts" user "Board Geometry/Outline")
		(27 "Margin" user)
		(31 "F.CrtYd" user "Package Geometry/Place Bound Top")
		(29 "B.CrtYd" user "Package Geometry/Place Bound Bottom")
		(35 "F.Fab" user "Ref Des/Assembly Top")
		(33 "B.Fab" user "Ref Des/Assembly Bottom")
	)
	(footprint ""
		(layer "F.Cu")
		(at 364.50143 -244.03177 90)
		(property "Reference" "C1009"
			(at 0 0 90)
			(layer "F.SilkS")
			(hide yes)
			(effects
				(font
					(size 1.27 1.27)
				)
			)
		)
		(property "Value" ""
			(at 0 0 90)
			(layer "F.Fab")
			(effects
				(font
					(size 1.27 1.27)
				)
			)
		)
		(duplicate_pad_numbers_are_jumpers no)
		(fp_line
			(start 0.7874 -0.4064)
			(end 0.7874 0.4064)
			(stroke
				(width 0.1524)
				(type default)
			)
			(layer "F.SilkS")
		)
		(fp_line
			(start -0.7874 -0.4064)
			(end 0.7874 -0.4064)
			(stroke
				(width 0.1524)
				(type default)
			)
			(layer "F.SilkS")
		)
		(fp_line
			(start 0.7874 0.4064)
			(end -0.7874 0.4064)
			(stroke
				(width 0.1524)
				(type default)
			)
			(layer "F.SilkS")
		)
		(fp_line
			(start -0.7874 0.4064)
			(end -0.7874 -0.4064)
			(stroke
				(width 0.1524)
				(type default)
			)
			(layer "F.SilkS")
		)
		(fp_line
			(start -0.12065 -0.305054)
			(end -0.12065 -0.2794)
			(stroke
				(width 0.1)
				(type default)
			)
			(layer "F.Fab")
		)
		(fp_line
			(start -0.67945 -0.305054)
			(end -0.12065 -0.305054)
			(stroke
				(width 0.1)
				(type default)
			)
			(layer "F.Fab")
		)
		(fp_line
			(start 0.67945 -0.3048)
			(end 0.67945 0.3048)
			(stroke
				(width 0.1)
				(type default)
			)
			(layer "F.Fab")
		)
		(fp_line
			(start 0.12065 -0.3048)
			(end 0.67945 -0.3048)
			(stroke
				(width 0.1)
				(type default)
			)
			(layer "F.Fab")
		)
		(fp_line
			(start 0.12065 -0.2794)
			(end 0.12065 -0.3048)
			(stroke
				(width 0.1)
				(type default)
			)
			(layer "F.Fab")
		)
		(fp_line
			(start -0.12065 -0.2794)
			(end 0.12065 -0.2794)
			(stroke
				(width 0.1)
				(type default)
			)
			(layer "F.Fab")
		)
		(fp_line
			(start 0.120396 0.2794)
			(end -0.12065 0.2794)
			(stroke
				(width 0.1)
				(type default)
			)
			(layer "F.Fab")
		)
		(fp_line
			(start -0.12065 0.2794)
			(end -0.12065 0.3048)
			(stroke
				(width 0.1)
				(type default)
			)
			(layer "F.Fab")
		)
		(fp_line
			(start 0.67945 0.3048)
			(end 0.120396 0.3048)
			(stroke
				(width 0.1)
				(type default)
			)
			(layer "F.Fab")
		)
		(fp_line
			(start 0.120396 0.3048)
			(end 0.120396 0.2794)
			(stroke
				(width 0.1)
				(type default)
			)
			(layer "F.Fab")
		)
		(fp_line
			(start -0.12065 0.3048)
			(end -0.67945 0.3048)
			(stroke
				(width 0.1)
				(type default)
			)
			(layer "F.Fab")
		)
		(fp_line
			(start -0.67945 0.3048)
			(end -0.67945 -0.305054)
			(stroke
				(width 0.1)
				(type default)
			)
			(layer "F.Fab")
		)
		(pad "1" smd circle
			(at -0.40005 0 90)
			(size 0 0)
			(layers "F.Cu" "F.Mask" "F.Paste")
			(net "PVCCIN_CPU0")
		)
		(pad "2" smd circle
			(at 0.40005 0 90)
			(size 0 0)
			(layers "F.Cu" "F.Mask" "F.Paste")
			(net "GND")
		)
	)
	(footprint ""
		(layer "F.Cu")
		(at 218.694 -96.103948 180)
		(property "Reference" "R4620"
			(at 0 0 180)
			(layer "F.SilkS")
			(hide yes)
			(effects
				(font
					(size 1.27 1.27)
				)
			)
		)
		(property "Value" ""
			(at 0 0 180)
			(layer "F.Fab")
			(effects
				(font
					(size 1.27 1.27)
				)
			)
		)
		(duplicate_pad_numbers_are_jumpers no)
		(fp_line
			(start 0.7874 0.4064)
			(end -0.7874 0.4064)
			(stroke
				(width 0.1524)
				(type default)
			)
			(layer "F.SilkS")
		)
		(fp_line
			(start 0.7874 -0.4064)
			(end 0.7874 0.4064)
			(stroke
				(width 0.1524)
				(type default)
			)
			(layer "F.SilkS")
		)
		(fp_line
			(start -0.7874 0.4064)
			(end -0.7874 -0.4064)
			(stroke
				(width 0.1524)
				(type default)
			)
			(layer "F.SilkS")
		)
		(fp_line
			(start -0.7874 -0.4064)
			(end 0.7874 -0.4064)
			(stroke
				(width 0.1524)
				(type default)
			)
			(layer "F.SilkS")
		)
		(fp_line
			(start 0.67945 0.3048)
			(end 0.120396 0.3048)
			(stroke
				(width 0.1)
				(type default)
			)
			(layer "F.Fab")
		)
		(fp_line
			(start 0.67945 -0.3048)
			(end 0.67945 0.3048)
			(stroke
				(width 0.1)
				(type default)
			)
			(layer "F.Fab")
		)
		(fp_line
			(start 0.12065 -0.2794)
			(end 0.12065 -0.3048)
			(stroke
				(width 0.1)
				(type default)
			)
			(layer "F.Fab")
		)
		(fp_line
			(start 0.12065 -0.3048)
			(end 0.67945 -0.3048)
			(stroke
				(width 0.1)
				(type default)
			)
			(layer "F.Fab")
		)
		(fp_line
			(start 0.120396 0.3048)
			(end 0.120396 0.2794)
			(stroke
				(width 0.1)
				(type default)
			)
			(layer "F.Fab")
		)
		(fp_line
			(start 0.120396 0.2794)
			(end -0.12065 0.2794)
			(stroke
				(width 0.1)
				(type default)
			)
			(layer "F.Fab")
		)
		(fp_line
			(start -0.12065 0.3048)
			(end -0.67945 0.3048)
			(stroke
				(width 0.1)
				(type default)
			)
			(layer "F.Fab")
		)
		(fp_line
			(start -0.12065 0.2794)
			(end -0.12065 0.3048)
			(stroke
				(width 0.1)
				(type default)
			)
			(layer "F.Fab")
		)
		(fp_line
			(start -0.12065 -0.2794)
			(end 0.12065 -0.2794)
			(stroke
				(width 0.1)
				(type default)
			)
			(layer "F.Fab")
		)
		(fp_line
			(start -0.12065 -0.305054)
			(end -0.12065 -0.2794)
			(stroke
				(width 0.1)
				(type default)
			)
			(layer "F.Fab")
		)
		(fp_line
			(start -0.67945 0.3048)
			(end -0.67945 -0.305054)
			(stroke
				(width 0.1)
				(type default)
			)
			(layer "F.Fab")
		)
		(fp_line
			(start -0.67945 -0.305054)
			(end -0.12065 -0.305054)
			(stroke
				(width 0.1)
				(type default)
			)
			(layer "F.Fab")
		)
		(pad "1" smd circle
			(at -0.40005 0 180)
			(size 0 0)
			(layers "F.Cu" "F.Mask" "F.Paste")
			(net "P3V3_AUX")
		)
		(pad "2" smd circle
			(at 0.40005 0 180)
			(size 0 0)
			(layers "F.Cu" "F.Mask" "F.Paste")
			(net "IRQ_UV_DETECT_N")
		)
	)
)
